FILE_TYPE = CONNECTIVITY;
{Allegro Design Entry HDL 17.2-2016 S081 (4005846) 1/11/2022}
"PAGE_NUMBER" = 36;
0"NC";
1"VCCIO2\g";
2"VCCIO2\g";
3"VCCIO2\g";
4"IRQ_SML0_ALERT_R_N";
5"CLK_GEN2_BMC_RC_OE_N";
6"FM_BMC_DEBUG_SW_R2_N";
7"FM_BMC_CRASHLOG_TRIG_R2_N";
8"IRQ_PCH_TPM_SPI_R2_N";
9"FM_BMC_SUSACK_R2_N";
10"PWRGD_DSW_PWROK_R2";
11"FM_DEBUG_PORT_R2_PRSNT_N";
12"TP_PLD_C13";
13"FM_SOL_UART_CH_SEL_R2";
14"FM_P12V_HSC_ENABLE_R2";
15"RST_WDTRST_PLD_R2_N";
16"RST_PFR_OVR_RTC_R";
17"RST_ROT_CPU_N";
18"SMB_BMC_MM16_R5_SDA";
19"SMB_BMC_MM16_R5_SCL";
20"FM_UARTSW_MSB_N";
21"FM_UARTSW_LSB_N";
22"FM_UARTSW_LSB_R_N";
23"FM_UARTSW_MSB_R_N";
24"PWRGD_P1V0_AUX_R1";
25"PWRGD_P1V2_AUX_R1";
26"PWRGD_P3V3_RGM";
27"PWRGD_P1V8_AUX";
28"PWRGD_P1V0_AUX";
29"PWRGD_P1V2_AUX";
30"PWRGD_P1V8_AUX_R1";
31"PWRGD_P3V3_RGM_R1";
32"FM_BMC_UARTSW_LSB_N";
33"FM_BMC_UARTSW_MSB_N";
34"PU_FPGA_NCONFIG";
35"FM_BMC_CPU_FBRK_OUT_R_N";
36"FM_BMC_DEBUG_SW_N";
37"IRQ_PCH_TPM_SPI_N";
38"FM_BMC_CRASHLOG_TRIG_N";
39"FM_BMC_SUSACK_N";
40"RST_WDTRST_PLD_N";
41"FM_DEBUG_PORT_PRSNT_N";
42"NC_FM_PFR_NO_SERVICE_ACT_N";
43"FM_HDD_LED_N";
44"FM_PCH_BEEP_LED";
45"GPU_NVS_PWR_BRAKE_R_N";
46"GPU_WP_HW_CTRL_R_N";
47"BMC_MONITER";
48"FM_PFR_DSW_PWROK_N";
49"NC_FM_PFR_UPDATE_N";
50"FM_JTAG_TCK_MUX_BMC_SEL";
51"PU_PB25A";
52"SMB_BMC_MM16_R4_SDA";
53"FM_P12V_HSC_ENABLE";
54"SMB_BMC_MM16_R4_SCL";
55"GPU_FPGA_RST_N";
56"CLK_BUF1_GPU_FPGA_OE_R_N";
57"PWRGD_DSW_PWROK";
58"FM_SOL_UART_CH_SEL";
%"LCMXO3LF2100C5BG256C"
"3","(-4800,4150)","0","pure_quanta","I1";
;
PART_TYPE"SMLF"
MATERIAL"IC"
PART_NUMBER"AJ021000T03"
VALUE"LCMXO3LF-2100C-5BG256C"
CDS_LIB"pure_quanta"
CDS_LMAN_SYM_OUTLINE"-625,1325,625,-1325"
NEEDS_NO_SIZE"TRUE"
LOCATION"U25"
$SEC"3"
CDS_SEC"3";
"VCCIO2_N5"
$PN"N5"1;
"VCCIO2_N12"
$PN"N12"1;
"VCCIO2_K9"
$PN"K9"3;
"VCCIO2_K8"
$PN"K8"3;
"PB9B"
$PN"P7"46;
"PB9A"
$PN"R7"45;
"PB8B||SO||SPISO"
$PN"T6"44;
"PB8A||MCLK||CCLK"
$PN"P6"43;
"PB8D"
$PN"L7"42;
"PB8C"
$PN"N6"6;
"PB6B"
$PN"R6"7;
"PB6A"
$PN"T5"8;
"PB6D"
$PN"R4"9;
"PB6C"
$PN"T3"15;
"PB5B"
$PN"P5"12;
"PB5A||CSSPIN"
$PN"R5"11;
"PB3D"
$PN"R3"10;
"PB3C"
$PN"T2"13;
"PB3B"
$PN"T4"0;
"PB3A"
$PN"P4"14;
"PB25D"
$PN"R14"52;
"PB25C"
$PN"T15"54;
"PB25B||SI||SISPI"
$PN"P13"0;
"PB25A||SN"
$PN"R12"51;
"PB24B"
$PN"T13"0;
"PB24A"
$PN"P12"0;
"PB22B"
$PN"T12"0;
"PB22A"
$PN"R11"0;
"PB22D"
$PN"T14"0;
"PB22C"
$PN"R13"0;
"PB21D"
$PN"N11"0;
"PB21C"
$PN"M10"34;
"PB21B"
$PN"P11"0;
"PB21A"
$PN"T11"0;
"PB19B"
$PN"R10"0;
"PB19A"
$PN"P10"0;
"PB19D"
$PN"M11"0;
"PB19C"
$PN"N10"0;
"PB18D"
$PN"L10"23;
"PB18C"
$PN"M9"22;
"PB18B"
$PN"T10"0;
"PB18A"
$PN"R9"0;
"PB16B||PCLKC2_1"
$PN"P9"24;
"PB16A||PCLKT2_1"
$PN"T9"25;
"PB16D"
$PN"N9"31;
"PB16C"
$PN"M8"30;
"PB12D"
$PN"L9"35;
"PB12C"
$PN"N8"56;
"PB12B"
$PN"T8"50;
"PB12A"
$PN"P8"55;
"PB11B||PCLKC2_0"
$PN"R8"49;
"PB11A||PCLKT2_0"
$PN"T7"16;
"PB11D"
$PN"L8"48;
"PB11C"
$PN"M6"47;
"PB9D"
$PN"N7"4;
"PB9C"
$PN"M7"5;
%"Q_RES"
"1","(-7250,4675)","0","pure_quanta","I10";
;
VALUE"0"
MATERIAL"CHIP"
PART_NUMBER"CS00002JB13"
PACK_TYPE"0402LF"
WATTAGE"1/16W"
TOLERANCE"5%"
SEC_TYPE"0402LF"
CDS_LIB"pure_quanta"
LOCATION"R746"
SEC"1";
"B"
$PN"2"8;
"A"
$PN"1"37;
%"Q_RES"
"1","(-7250,5275)","0","pure_quanta","I2";
;
VALUE"0"
MATERIAL"CHIP"
PART_NUMBER"CS00002JB13"
PACK_TYPE"0402LF"
WATTAGE"1/16W"
TOLERANCE"5%"
CDS_LIB"pure_quanta"
SEC_TYPE"0402LF"
LOCATION"R575"
SEC"1";
"B"
$PN"2"14;
"A"
$PN"1"53;
%"Q_RES"
"1","(-7250,5125)","0","pure_quanta","I3";
;
VALUE"0"
MATERIAL"CHIP"
PART_NUMBER"CS00002JB13"
PACK_TYPE"0402LF"
WATTAGE"1/16W"
TOLERANCE"5%"
CDS_LIB"pure_quanta"
SEC_TYPE"0402LF"
LOCATION"R577"
SEC"1";
"B"
$PN"2"13;
"A"
$PN"1"58;
%"Q_RES"
"1","(-2575,5275)","0","pure_quanta","I33";
;
VALUE"0"
MATERIAL"CHIP"
SEC_TYPE"0402LF"
CDS_LIB"pure_quanta"
TOLERANCE"5%"
WATTAGE"1/16W"
PACK_TYPE"0402LF"
PART_NUMBER"CS00002JB13"
LOCATION"R321"
SEC"1";
"B"
$PN"2"27;
"A"
$PN"1"30;
%"Q_RES"
"1","(-2575,5125)","0","pure_quanta","I34";
;
VALUE"0"
MATERIAL"CHIP"
CDS_LIB"pure_quanta"
SEC_TYPE"0402LF"
TOLERANCE"5%"
WATTAGE"1/16W"
PACK_TYPE"0402LF"
PART_NUMBER"CS00002JB13"
LOCATION"R323"
SEC"1";
"B"
$PN"2"29;
"A"
$PN"1"25;
%"Q_RES"
"1","(-2575,5225)","0","pure_quanta","I35";
;
VALUE"0"
MATERIAL"CHIP"
SEC_TYPE"0402LF"
CDS_LIB"pure_quanta"
TOLERANCE"5%"
WATTAGE"1/16W"
PACK_TYPE"0402LF"
PART_NUMBER"CS00002JB13"
LOCATION"R322"
SEC"1";
"B"
$PN"2"26;
"A"
$PN"1"31;
%"Q_RES"
"1","(-2575,5075)","0","pure_quanta","I36";
;
VALUE"0"
MATERIAL"CHIP"
SEC_TYPE"0402LF"
CDS_LIB"pure_quanta"
TOLERANCE"5%"
WATTAGE"1/16W"
PACK_TYPE"0402LF"
PART_NUMBER"CS00002JB13"
LOCATION"R379"
SEC"1";
"B"
$PN"2"28;
"A"
$PN"1"24;
%"UNIVERSAL_POWER"
"1","(-5950,3175)","0","logical_power","I37";
;
HDL_POWER"VCCIO2"
CDS_LIB"logical_power";
"A"3;
%"UNIVERSAL_POWER"
"1","(-3650,3175)","0","logical_power","I38";
;
HDL_POWER"VCCIO2"
CDS_LIB"logical_power";
"A"1;
%"Q_RES"
"1","(-2575,4825)","0","pure_quanta","I42";
;
VALUE"0"
MATERIAL"CHIP"
SEC_TYPE"0402LF"
CDS_LIB"pure_quanta"
TOLERANCE"5%"
WATTAGE"1/16W"
PACK_TYPE"0402LF"
PART_NUMBER"CS00002JB13"
LOCATION"R898"
SEC"1";
"B"
$PN"2"21;
"A"
$PN"1"22;
%"Q_RES"
"1","(-2575,4775)","0","pure_quanta","I43";
;
VALUE"0"
MATERIAL"CHIP"
CDS_LIB"pure_quanta"
SEC_TYPE"0402LF"
PART_NUMBER"CS00002JB13"
PACK_TYPE"0402LF"
WATTAGE"1/16W"
TOLERANCE"5%"
LOCATION"R899"
SEC"1";
"B"
$PN"2"20;
"A"
$PN"1"23;
%"Q_RES"
"1","(-2575,4525)","0","pure_quanta","I46";
;
MATERIAL"CHIP"
VALUE"0"
TOLERANCE"5%"
WATTAGE"1/16W"
PACK_TYPE"0402LF"
PART_NUMBER"CS00002JB13"
CDS_LIB"pure_quanta"
$LOCATION"R220"
CDS_LOCATION"R220"
$SEC"1"
CDS_SEC"1";
"B"
$PN"2"20;
"A"
$PN"1"33;
%"Q_RES"
"1","(-2575,4575)","0","pure_quanta","I47";
;
MATERIAL"CHIP"
VALUE"0"
CDS_LIB"pure_quanta"
PART_NUMBER"CS00002JB13"
PACK_TYPE"0402LF"
WATTAGE"1/16W"
TOLERANCE"5%"
$LOCATION"R134"
CDS_LOCATION"R134"
$SEC"1"
CDS_SEC"1";
"B"
$PN"2"21;
"A"
$PN"1"32;
%"Q_RES"
"2","(-2750,3700)","0","pure_quanta","I50";
;
PART_NUMBER"CS31002FB08"
VALUE"10K"
MATERIAL"CHIP"
WATTAGE"1/16W"
TOLERANCE"1%"
PACK_TYPE"0402LF"
CDS_LIB"pure_quanta"
$LOCATION"R288"
CDS_LOCATION"R288"
$SEC"1"
CDS_SEC"1";
"A"
$PN"1"2;
"B"
$PN"2"51;
%"UNIVERSAL_POWER"
"1","(-2750,3875)","0","logical_power","I51";
;
HDL_POWER"VCCIO2"
CDS_LIB"logical_power";
"A"2;
%"Q_RES"
"1","(-2525,3375)","0","pure_quanta","I57";
;
VALUE"0"
MATERIAL"CHIP"
SEC_TYPE"0402LF"
CDS_LIB"pure_quanta"
TOLERANCE"5%"
WATTAGE"1/16W"
PACK_TYPE"0402LF"
PART_NUMBER"CS00002JB13"
$LOCATION"R114"
CDS_LOCATION"R114"
SEC"1";
"B"
$PN"2"18;
"A"
$PN"1"52;
%"Q_RES"
"1","(-2525,3425)","0","pure_quanta","I58";
;
VALUE"0"
MATERIAL"CHIP"
CDS_LIB"pure_quanta"
SEC_TYPE"0402LF"
TOLERANCE"5%"
WATTAGE"1/16W"
PACK_TYPE"0402LF"
PART_NUMBER"CS00002JB13"
$LOCATION"R105"
CDS_LOCATION"R105"
SEC"1";
"B"
$PN"2"19;
"A"
$PN"1"54;
%"Q_RES"
"1","(-7250,4975)","0","pure_quanta","I7";
;
VALUE"0"
MATERIAL"CHIP"
PART_NUMBER"CS00002JB13"
PACK_TYPE"0402LF"
WATTAGE"1/16W"
TOLERANCE"5%"
CDS_LIB"pure_quanta"
SEC_TYPE"0402LF"
LOCATION"R579"
SEC"1";
"B"
$PN"2"11;
"A"
$PN"1"41;
%"Q_RES"
"1","(-1900,4225)","0","pure_quanta","I78";
;
VALUE"0"
MATERIAL"CHIP"
PART_NUMBER"CS00002JB13"
PACK_TYPE"0402LF"
WATTAGE"1/16W"
TOLERANCE"5%"
CDS_LIB"pure_quanta"
LOCATION"R748"
$SEC"1"
CDS_SEC"1";
"B"
$PN"2"17;
"A"
$PN"1"34;
%"Q_RES"
"1","(-7250,5075)","0","pure_quanta","I8";
;
VALUE"0"
MATERIAL"CHIP"
PART_NUMBER"CS00002JB13"
PACK_TYPE"0402LF"
WATTAGE"1/16W"
TOLERANCE"5%"
CDS_LIB"pure_quanta"
SEC_TYPE"0402LF"
LOCATION"R578"
SEC"1";
"B"
$PN"2"10;
"A"
$PN"1"57;
%"Q_RES"
"1","(-7250,4825)","0","pure_quanta","I80";
;
VALUE"33.2"
MATERIAL"CHIP"
TOLERANCE"1%"
PART_NUMBER"CS03322FB03"
WATTAGE"1/16W"
PACK_TYPE"0402LF"
CDS_LIB"pure_quanta"
LOCATION"R635"
$SEC"1"
CDS_SEC"1";
"B"
$PN"2"15;
"A"
$PN"1"40;
%"Q_RES"
"1","(-7250,4775)","0","pure_quanta","I81";
;
VALUE"33.2"
MATERIAL"CHIP"
TOLERANCE"1%"
PART_NUMBER"CS03322FB03"
WATTAGE"1/16W"
PACK_TYPE"0402LF"
CDS_LIB"pure_quanta"
LOCATION"R445"
$SEC"1"
CDS_SEC"1";
"B"
$PN"2"9;
"A"
$PN"1"39;
%"Q_RES"
"1","(-7250,4525)","0","pure_quanta","I82";
;
VALUE"33.2"
MATERIAL"CHIP"
TOLERANCE"1%"
PART_NUMBER"CS03322FB03"
WATTAGE"1/16W"
PACK_TYPE"0402LF"
CDS_LIB"pure_quanta"
LOCATION"R750"
$SEC"1"
CDS_SEC"1";
"B"
$PN"2"6;
"A"
$PN"1"36;
%"Q_RES"
"1","(-7250,4625)","0","pure_quanta","I9";
;
VALUE"0"
MATERIAL"CHIP"
PART_NUMBER"CS00002JB13"
PACK_TYPE"0402LF"
WATTAGE"1/16W"
TOLERANCE"5%"
SEC_TYPE"0402LF"
CDS_LIB"pure_quanta"
LOCATION"R747"
SEC"1";
"B"
$PN"2"7;
"A"
$PN"1"38;
END.
